# S9S_MB_2U (Grand Teton) — schematic netlist excerpt (pin names and nets, part order shuffled) for the footprints in the layout excerpt that follows; sources: Cadence DE-HDL packaged netlist, KiCad conversion of 03242023_DA0F0TMBIJ0_F0T_Motherboard_J_brd_V01_OCP.brd

R4501  Q_RES  0 5% CHIP  pkg 0402LF  page 212 : A = CLK_GEN2_XTAL_IN_R ; B = CLK_GEN2_XTAL_IN

U194  LTC4307CMS8  IC  pkg MSOP8  page 234
  ENABLE  = SMB_BMC_GPU_EN_R1
  SCL_OUT  = SMB_1_BMC_GPU_BUF_R_SCL
  SCL_IN  = SMB_1_BMC_GPU_R_SCL
  GND  = GND
  READY  = NC
  SDA_IN  = SMB_1_BMC_GPU_R_SDA
  SDA_OUT  = SMB_1_BMC_GPU_BUF_R_SDA
  VCC  = P3V3_AUX

(kicad_pcb
	(version 20260206)
	(generator "pcbnew")
	(generator_version "10.0")
	(general
		(thickness 1.6)
		(legacy_teardrops no)
	)
	(paper "A4")
	(title_block
		(title "03242023_DA0F0TMBIJ0_F0T_Motherboard_J_brd_V01_OCP.brd")
		(comment 1 "Grand Teton / footprints 1260-1261 of 6105")
	)
	(layers
		(0 "F.Cu" signal "TOP")
		(4 "In1.Cu" signal "GND")
		(6 "In2.Cu" signal "IN1")
		(8 "In3.Cu" signal "GND1")
		(10 "In4.Cu" signal "IN2")
		(12 "In5.Cu" signal "GND2")
		(14 "In6.Cu" signal "IN3")
		(16 "In7.Cu" signal "GND3")
		(18 "In8.Cu" signal "VCC")
		(20 "In9.Cu" signal "VCC1")
		(22 "In10.Cu" signal "GND4")
		(24 "In11.Cu" signal "IN4")
		(26 "In12.Cu" signal "GND5")
		(28 "In13.Cu" signal "IN5")
		(30 "In14.Cu" signal "GND6")
		(32 "In15.Cu" signal "IN6")
		(34 "In16.Cu" signal "GND7")
		(2 "B.Cu" signal "BOTTOM")
		(9 "F.Adhes" user "F.Adhesive")
		(11 "B.Adhes" user "B.Adhesive")
		(13 "F.Paste" user "Package Geometry/Pastemask Top")
		(15 "B.Paste" user "Package Geometry/Pastemask Bottom")
		(5 "F.SilkS" user "Ref Des/Silkscreen Top")
		(7 "B.SilkS" user "Ref Des/Silkscreen Bottom")
		(1 "F.Mask" user "Board Geometry/Soldermask Top")
		(3 "B.Mask" user "Board Geometry/Soldermask Bottom")
		(17 "Dwgs.User" user "User.Drawings")
		(19 "Cmts.User" user "User.Comments")
		(21 "Eco1.User" user "User.Eco1")
		(23 "Eco2.User" user "User.Eco2")
		(25 "Edge.Cuts" user "Board Geometry/Outline")
		(27 "Margin" user)
		(31 "F.CrtYd" user "Package Geometry/Place Bound Top")
		(29 "B.CrtYd" user "Package Geometry/Place Bound Bottom")
		(35 "F.Fab" user "Ref Des/Assembly Top")
		(33 "B.Fab" user "Ref Des/Assembly Bottom")
	)
	(footprint ""
		(layer "F.Cu")
		(at 239.7125 -249.339608 -90)
		(property "Reference" "R4501"
			(at 0 0 270)
			(layer "F.SilkS")
			(hide yes)
			(effects
				(font
					(size 1.27 1.27)
				)
			)
		)
		(property "Value" ""
			(at 0 0 270)
			(layer "F.Fab")
			(effects
				(font
					(size 1.27 1.27)
				)
			)
		)
		(duplicate_pad_numbers_are_jumpers no)
		(fp_line
			(start -0.7874 0.4064)
			(end -0.7874 -0.4064)
			(stroke
				(width 0.1524)
				(type default)
			)
			(layer "F.SilkS")
		)
		(fp_line
			(start 0.7874 0.4064)
			(end -0.7874 0.4064)
			(stroke
				(width 0.1524)
				(type default)
			)
			(layer "F.SilkS")
		)
		(fp_line
			(start -0.7874 -0.4064)
			(end 0.7874 -0.4064)
			(stroke
				(width 0.1524)
				(type default)
			)
			(layer "F.SilkS")
		)
		(fp_line
			(start 0.7874 -0.4064)
			(end 0.7874 0.4064)
			(stroke
				(width 0.1524)
				(type default)
			)
			(layer "F.SilkS")
		)
		(fp_line
			(start -0.67945 0.3048)
			(end -0.67945 -0.305054)
			(stroke
				(width 0.1)
				(type default)
			)
			(layer "F.Fab")
		)
		(fp_line
			(start -0.12065 0.3048)
			(end -0.67945 0.3048)
			(stroke
				(width 0.1)
				(type default)
			)
			(layer "F.Fab")
		)
		(fp_line
			(start 0.120396 0.3048)
			(end 0.120396 0.2794)
			(stroke
				(width 0.1)
				(type default)
			)
			(layer "F.Fab")
		)
		(fp_line
			(start 0.67945 0.3048)
			(end 0.120396 0.3048)
			(stroke
				(width 0.1)
				(type default)
			)
			(layer "F.Fab")
		)
		(fp_line
			(start -0.12065 0.2794)
			(end -0.12065 0.3048)
			(stroke
				(width 0.1)
				(type default)
			)
			(layer "F.Fab")
		)
		(fp_line
			(start 0.120396 0.2794)
			(end -0.12065 0.2794)
			(stroke
				(width 0.1)
				(type default)
			)
			(layer "F.Fab")
		)
		(fp_line
			(start -0.12065 -0.2794)
			(end 0.12065 -0.2794)
			(stroke
				(width 0.1)
				(type default)
			)
			(layer "F.Fab")
		)
		(fp_line
			(start 0.12065 -0.2794)
			(end 0.12065 -0.3048)
			(stroke
				(width 0.1)
				(type default)
			)
			(layer "F.Fab")
		)
		(fp_line
			(start 0.12065 -0.3048)
			(end 0.67945 -0.3048)
			(stroke
				(width 0.1)
				(type default)
			)
			(layer "F.Fab")
		)
		(fp_line
			(start 0.67945 -0.3048)
			(end 0.67945 0.3048)
			(stroke
				(width 0.1)
				(type default)
			)
			(layer "F.Fab")
		)
		(fp_line
			(start -0.67945 -0.305054)
			(end -0.12065 -0.305054)
			(stroke
				(width 0.1)
				(type default)
			)
			(layer "F.Fab")
		)
		(fp_line
			(start -0.12065 -0.305054)
			(end -0.12065 -0.2794)
			(stroke
				(width 0.1)
				(type default)
			)
			(layer "F.Fab")
		)
		(pad "1" smd circle
			(at -0.40005 0 270)
			(size 0 0)
			(layers "F.Cu" "F.Mask" "F.Paste")
			(net "CLK_GEN2_XTAL_IN_R")
		)
		(pad "2" smd circle
			(at 0.40005 0 270)
			(size 0 0)
			(layers "F.Cu" "F.Mask" "F.Paste")
			(net "CLK_GEN2_XTAL_IN")
		)
	)
	(footprint ""
		(layer "F.Cu")
		(at 45.622972 -434.725318)
		(property "Reference" "U194"
			(at -2.747772 -2.051812 0)
			(unlocked yes)
			(layer "F.SilkS")
			(effects
				(font
					(size 0.7874 0.5842)
					(thickness 0.1524)
				)
				(justify left)
			)
		)
		(property "Value" ""
			(at 0 0 0)
			(layer "F.Fab")
			(effects
				(font
					(size 1.27 1.27)
				)
			)
		)
		(duplicate_pad_numbers_are_jumpers no)
		(fp_line
			(start -1.3716 -1.524)
			(end -0.508 -1.524)
			(stroke
				(width 0.1524)
				(type default)
			)
			(layer "F.SilkS")
		)
		(fp_line
			(start -1.3716 1.524)
			(end -1.3716 -1.524)
			(stroke
				(width 0.1524)
				(type default)
			)
			(layer "F.SilkS")
		)
		(fp_line
			(start -0.508 -1.524)
			(end 0 -1.016)
			(stroke
				(width 0.1524)
				(type default)
			)
			(layer "F.SilkS")
		)
		(fp_line
			(start 0 -1.016)
			(end 0.508 -1.524)
			(stroke
				(width 0.1524)
				(type default)
			)
			(layer "F.SilkS")
		)
		(fp_line
			(start 0.508 -1.524)
			(end 1.3716 -1.524)
			(stroke
				(width 0.1524)
				(type default)
			)
			(layer "F.SilkS")
		)
		(fp_line
			(start 1.3716 -1.524)
			(end 1.3716 1.524)
			(stroke
				(width 0.1524)
				(type default)
			)
			(layer "F.SilkS")
		)
		(fp_line
			(start 1.3716 1.524)
			(end -1.3716 1.524)
			(stroke
				(width 0.1524)
				(type default)
			)
			(layer "F.SilkS")
		)
		(fp_poly
			(pts
				(xy -3.6703 -1.331468) (xy -3.11658 -1.0033) (xy -3.6703 -0.706628)
			)
			(stroke
				(width 0)
				(type default)
			)
			(fill yes)
			(layer "F.SilkS")
		)
		(fp_line
			(start -2.54 -1.0668)
			(end -1.5494 -1.0668)
			(stroke
				(width 0.1)
				(type default)
			)
			(layer "F.Fab")
		)
		(fp_line
			(start -2.54 1.0668)
			(end -2.54 -1.0668)
			(stroke
				(width 0.1)
				(type default)
			)
			(layer "F.Fab")
		)
		(fp_line
			(start -1.5494 -1.524)
			(end 1.5494 -1.524)
			(stroke
				(width 0.1)
				(type default)
			)
			(layer "F.Fab")
		)
		(fp_line
			(start -1.5494 -1.0668)
			(end -1.5494 -1.524)
			(stroke
				(width 0.1)
				(type default)
			)
			(layer "F.Fab")
		)
		(fp_line
			(start -1.5494 1.0668)
			(end -2.54 1.0668)
			(stroke
				(width 0.1)
				(type default)
			)
			(layer "F.Fab")
		)
		(fp_line
			(start -1.5494 1.0668)
			(end -1.5494 -1.0668)
			(stroke
				(width 0.1)
				(type default)
			)
			(layer "F.Fab")
		)
		(fp_line
			(start -1.5494 1.524)
			(end -1.5494 1.0668)
			(stroke
				(width 0.1)
				(type default)
			)
			(layer "F.Fab")
		)
		(fp_line
			(start 1.5494 -1.524)
			(end 1.5494 -1.0668)
			(stroke
				(width 0.1)
				(type default)
			)
			(layer "F.Fab")
		)
		(fp_line
			(start 1.5494 -1.0668)
			(end 1.5494 1.0668)
			(stroke
				(width 0.1)
				(type default)
			)
			(layer "F.Fab")
		)
		(fp_line
			(start 1.5494 -1.0668)
			(end 2.54 -1.0668)
			(stroke
				(width 0.1)
				(type default)
			)
			(layer "F.Fab")
		)
		(fp_line
			(start 1.5494 1.0668)
			(end 1.5494 1.524)
			(stroke
				(width 0.1)
				(type default)
			)
			(layer "F.Fab")
		)
		(fp_line
			(start 1.5494 1.524)
			(end -1.5494 1.524)
			(stroke
				(width 0.1)
				(type default)
			)
			(layer "F.Fab")
		)
		(fp_line
			(start 2.54 -1.0668)
			(end 2.54 1.0668)
			(stroke
				(width 0.1)
				(type default)
			)
			(layer "F.Fab")
		)
		(fp_line
			(start 2.54 1.0668)
			(end 1.5494 1.0668)
			(stroke
				(width 0.1)
				(type default)
			)
			(layer "F.Fab")
		)
		(fp_poly
			(pts
				(xy -3.60172 -0.719328) (xy -3.60172 -1.344168) (xy -3.048 -1.016)
			)
			(stroke
				(width 0)
				(type default)
			)
			(fill yes)
			(layer "F.Fab")
		)
		(pad "1" smd rect
			(at -2.232406 -0.975106 270)
			(size 0.3556 1.4224)
			(layers "F.Cu" "F.Mask" "F.Paste")
			(net "SMB_BMC_GPU_EN_R1")
		)
		(pad "2" smd rect
			(at -2.232406 -0.32512 270)
			(size 0.3556 1.4224)
			(layers "F.Cu" "F.Mask" "F.Paste")
			(net "SMB_1_BMC_GPU_BUF_R_SCL")
		)
		(pad "3" smd rect
			(at -2.232406 0.32512 270)
			(size 0.3556 1.4224)
			(layers "F.Cu" "F.Mask" "F.Paste")
			(net "SMB_1_BMC_GPU_R_SCL")
		)
		(pad "4" smd rect
			(at -2.232406 0.975106 270)
			(size 0.3556 1.4224)
			(layers "F.Cu" "F.Mask" "F.Paste")
			(net "GND")
		)
		(pad "5" smd rect
			(at 2.232406 0.975106 270)
			(size 0.3556 1.4224)
			(layers "F.Cu" "F.Mask" "F.Paste")
			(net "Net_1936")
		)
		(pad "6" smd rect
			(at 2.232406 0.32512 270)
			(size 0.3556 1.4224)
			(layers "F.Cu" "F.Mask" "F.Paste")
			(net "SMB_1_BMC_GPU_R_SDA")
		)
		(pad "7" smd rect
			(at 2.232406 -0.32512 270)
			(size 0.3556 1.4224)
			(layers "F.Cu" "F.Mask" "F.Paste")
			(net "SMB_1_BMC_GPU_BUF_R_SDA")
		)
		(pad "8" smd rect
			(at 2.232406 -0.975106 270)
			(size 0.3556 1.4224)
			(layers "F.Cu" "F.Mask" "F.Paste")
			(net "P3V3_AUX")
		)
	)
)
